(kicad_pcb
	(version 20260206)
	(generator "pcbnew")
	(generator_version "10.0")
	(general
		(thickness 1.6)
		(legacy_teardrops no)
	)
	(paper "A4")
	(title_block
		(title "03242023_DA0F0TMBIJ0_F0T_Motherboard_J_brd_V01_OCP.brd")
		(comment 1 "Grand Teton / footprints 4466-4471 of 6105")
	)
	(layers
		(0 "F.Cu" signal "TOP")
		(4 "In1.Cu" signal "GND")
		(6 "In2.Cu" signal "IN1")
		(8 "In3.Cu" signal "GND1")
		(10 "In4.Cu" signal "IN2")
		(12 "In5.Cu" signal "GND2")
		(14 "In6.Cu" signal "IN3")
		(16 "In7.Cu" signal "GND3")
		(18 "In8.Cu" signal "VCC")
		(20 "In9.Cu" signal "VCC1")
		(22 "In10.Cu" signal "GND4")
		(24 "In11.Cu" signal "IN4")
		(26 "In12.Cu" signal "GND5")
		(28 "In13.Cu" signal "IN5")
		(30 "In14.Cu" signal "GND6")
		(32 "In15.Cu" signal "IN6")
		(34 "In16.Cu" signal "GND7")
		(2 "B.Cu" signal "BOTTOM")
		(9 "F.Adhes" user "F.Adhesive")
		(11 "B.Adhes" user "B.Adhesive")
		(13 "F.Paste" user "Package Geometry/Pastemask Top")
		(15 "B.Paste" user "Package Geometry/Pastemask Bottom")
		(5 "F.SilkS" user "Ref Des/Silkscreen Top")
		(7 "B.SilkS" user "Ref Des/Silkscreen Bottom")
		(1 "F.Mask" user "Board Geometry/Soldermask Top")
		(3 "B.Mask" user "Board Geometry/Soldermask Bottom")
		(17 "Dwgs.User" user "User.Drawings")
		(19 "Cmts.User" user "User.Comments")
		(21 "Eco1.User" user "User.Eco1")
		(23 "Eco2.User" user "User.Eco2")
		(25 "Edge.Cuts" user "Board Geometry/Outline")
		(27 "Margin" user)
		(31 "F.CrtYd" user "Package Geometry/Place Bound Top")
		(29 "B.CrtYd" user "Package Geometry/Place Bound Bottom")
		(35 "F.Fab" user "Ref Des/Assembly Top")
		(33 "B.Fab" user "Ref Des/Assembly Bottom")
	)
	(footprint ""
		(layer "B.Cu")
		(at 260.731508 2.923794 180)
		(property "Reference" "J121"
			(at 4.218178 -1.394206 270)
			(unlocked yes)
			(layer "B.SilkS")
			(effects
				(font
					(size 0.7874 0.5842)
					(thickness 0.1524)
				)
				(justify left mirror)
			)
		)
		(property "Value" ""
			(at 0 0 0)
			(layer "B.Fab")
			(effects
				(font
					(size 1.27 1.27)
				)
				(justify mirror)
			)
		)
		(duplicate_pad_numbers_are_jumpers no)
		(fp_line
			(start 1.2192 2.1082)
			(end 1.2192 -2.1082)
			(stroke
				(width 0.1524)
				(type default)
			)
			(layer "B.SilkS")
		)
		(fp_line
			(start 1.2192 -2.1082)
			(end -1.2192 -2.1082)
			(stroke
				(width 0.1524)
				(type default)
			)
			(layer "B.SilkS")
		)
		(fp_line
			(start -1.2192 2.1082)
			(end 1.2192 2.1082)
			(stroke
				(width 0.1524)
				(type default)
			)
			(layer "B.SilkS")
		)
		(fp_line
			(start -1.2192 -2.1082)
			(end -1.2192 2.1082)
			(stroke
				(width 0.1524)
				(type default)
			)
			(layer "B.SilkS")
		)
		(pad "" np_thru_hole circle
			(at -3.4671 -1.27 90)
			(size 1.0414 1.0414)
			(drill 1.0414)
			(layers "*.Cu" "*.Mask")
			(clearance 0.381)
			(thermal_gap 0.381)
		)
		(pad "" np_thru_hole circle
			(at -3.4671 1.27 90)
			(size 1.0414 1.0414)
			(drill 1.0414)
			(layers "*.Cu" "*.Mask")
			(clearance 0.381)
			(thermal_gap 0.381)
		)
		(pad "" np_thru_hole circle
			(at 2.8829 -1.27 90)
			(size 1.0414 1.0414)
			(drill 1.0414)
			(layers "*.Cu" "*.Mask")
			(clearance 0.381)
			(thermal_gap 0.381)
		)
		(pad "" np_thru_hole circle
			(at 2.8829 1.27 90)
			(size 1.0414 1.0414)
			(drill 1.0414)
			(layers "*.Cu" "*.Mask")
			(clearance 0.381)
			(thermal_gap 0.381)
		)
		(pad "1" smd rect
			(at -0.8255 -0.249936 90)
			(size 0.3048 0.508)
			(layers "B.Cu" "B.Mask" "B.Paste")
			(net "DELTA_L_85_10INCH_IN6_DN")
		)
		(pad "2" smd rect
			(at -0.8255 0.249936 90)
			(size 0.3048 0.508)
			(layers "B.Cu" "B.Mask" "B.Paste")
			(net "DELTA_L_85_10INCH_IN6_DP")
		)
		(pad "3" smd circle
			(at 0 0)
			(size 0 0)
			(layers "B.Cu" "B.Mask" "B.Paste")
			(net "DELTA_L_GND_1")
		)
		(zone
			(layers "F.Cu" "B.Cu" "In1.Cu" "In2.Cu" "In3.Cu" "In4.Cu" "In5.Cu" "In6.Cu"
				"In7.Cu" "In8.Cu" "In9.Cu" "In10.Cu" "In11.Cu" "In12.Cu" "In13.Cu" "In14.Cu"
				"In15.Cu" "In16.Cu"
			)
			(hatch none 0.5)
			(connect_pads
				(clearance 0)
			)
			(min_thickness 0.25)
			(keepout
				(tracks not_allowed)
				(vias allowed)
				(pads allowed)
				(copperpour not_allowed)
				(footprints allowed)
			)
			(placement
				(enabled no)
				(sheetname "")
			)
			(fill
				(thermal_gap 0.5)
				(thermal_bridge_width 0.5)
				(island_removal_mode 0)
			)
			(polygon
				(pts
					(arc
						(start 258.775708 1.653794)
						(mid 256.921508 1.653794)
						(end 258.775708 1.653794)
					)
				)
			)
		)
		(zone
			(layers "F.Cu" "B.Cu" "In1.Cu" "In2.Cu" "In3.Cu" "In4.Cu" "In5.Cu" "In6.Cu"
				"In7.Cu" "In8.Cu" "In9.Cu" "In10.Cu" "In11.Cu" "In12.Cu" "In13.Cu" "In14.Cu"
				"In15.Cu" "In16.Cu"
			)
			(hatch none 0.5)
			(connect_pads
				(clearance 0)
			)
			(min_thickness 0.25)
			(keepout
				(tracks not_allowed)
				(vias allowed)
				(pads allowed)
				(copperpour not_allowed)
				(footprints allowed)
			)
			(placement
				(enabled no)
				(sheetname "")
			)
			(fill
				(thermal_gap 0.5)
				(thermal_bridge_width 0.5)
				(island_removal_mode 0)
			)
			(polygon
				(pts
					(arc
						(start 258.775708 4.193794)
						(mid 256.921508 4.193794)
						(end 258.775708 4.193794)
					)
				)
			)
		)
		(zone
			(layers "F.Cu" "B.Cu" "In1.Cu" "In2.Cu" "In3.Cu" "In4.Cu" "In5.Cu" "In6.Cu"
				"In7.Cu" "In8.Cu" "In9.Cu" "In10.Cu" "In11.Cu" "In12.Cu" "In13.Cu" "In14.Cu"
				"In15.Cu" "In16.Cu"
			)
			(hatch none 0.5)
			(connect_pads
				(clearance 0)
			)
			(min_thickness 0.25)
			(keepout
				(tracks not_allowed)
				(vias allowed)
				(pads allowed)
				(copperpour not_allowed)
				(footprints allowed)
			)
			(placement
				(enabled no)
				(sheetname "")
			)
			(fill
				(thermal_gap 0.5)
				(thermal_bridge_width 0.5)
				(island_removal_mode 0)
			)
			(polygon
				(pts
					(arc
						(start 265.125708 1.653794)
						(mid 263.271508 1.653794)
						(end 265.125708 1.653794)
					)
				)
			)
		)
		(zone
			(layers "F.Cu" "B.Cu" "In1.Cu" "In2.Cu" "In3.Cu" "In4.Cu" "In5.Cu" "In6.Cu"
				"In7.Cu" "In8.Cu" "In9.Cu" "In10.Cu" "In11.Cu" "In12.Cu" "In13.Cu" "In14.Cu"
				"In15.Cu" "In16.Cu"
			)
			(hatch none 0.5)
			(connect_pads
				(clearance 0)
			)
			(min_thickness 0.25)
			(keepout
				(tracks not_allowed)
				(vias allowed)
				(pads allowed)
				(copperpour not_allowed)
				(footprints allowed)
			)
			(placement
				(enabled no)
				(sheetname "")
			)
			(fill
				(thermal_gap 0.5)
				(thermal_bridge_width 0.5)
				(island_removal_mode 0)
			)
			(polygon
				(pts
					(arc
						(start 265.125708 4.193794)
						(mid 263.271508 4.193794)
						(end 265.125708 4.193794)
					)
				)
			)
		)
		(zone
			(layer "B.Cu")
			(hatch none 0.5)
			(connect_pads
				(clearance 0)
			)
			(min_thickness 0.25)
			(keepout
				(tracks not_allowed)
				(vias allowed)
				(pads allowed)
				(copperpour not_allowed)
				(footprints allowed)
			)
			(placement
				(enabled no)
				(sheetname "")
			)
			(fill
				(thermal_gap 0.5)
				(thermal_bridge_width 0.5)
				(island_removal_mode 0)
			)
			(polygon
				(pts
					(xy 261.849108 3.472434) (xy 261.849108 3.37693) (xy 261.252208 3.37693) (xy 261.252208 2.97053)
					(xy 261.849108 2.97053) (xy 261.849108 2.877058) (xy 261.252208 2.877058) (xy 261.252208 2.470658)
					(xy 261.849108 2.470658) (xy 261.849108 2.375154) (xy 261.150608 2.375154) (xy 261.150608 3.472434)
				)
			)
		)
	)
	(footprint ""
		(layer "B.Cu")
		(at 157.686756 -39.871904 90)
		(property "Reference" "C2319"
			(at 0 0 90)
			(layer "B.SilkS")
			(hide yes)
			(effects
				(font
					(size 1.27 1.27)
				)
				(justify mirror)
			)
		)
		(property "Value" ""
			(at 0 0 90)
			(layer "B.Fab")
			(effects
				(font
					(size 1.27 1.27)
				)
				(justify mirror)
			)
		)
		(duplicate_pad_numbers_are_jumpers no)
		(fp_line
			(start 0.7874 -0.4064)
			(end -0.7874 -0.4064)
			(stroke
				(width 0.1524)
				(type default)
			)
			(layer "B.SilkS")
		)
		(fp_line
			(start -0.7874 -0.4064)
			(end -0.7874 0.4064)
			(stroke
				(width 0.1524)
				(type default)
			)
			(layer "B.SilkS")
		)
		(fp_line
			(start 0.7874 0.4064)
			(end 0.7874 -0.4064)
			(stroke
				(width 0.1524)
				(type default)
			)
			(layer "B.SilkS")
		)
		(fp_line
			(start -0.7874 0.4064)
			(end 0.7874 0.4064)
			(stroke
				(width 0.1524)
				(type default)
			)
			(layer "B.SilkS")
		)
		(fp_line
			(start 0.67945 -0.305054)
			(end 0.12065 -0.305054)
			(stroke
				(width 0.1)
				(type default)
			)
			(layer "B.Fab")
		)
		(fp_line
			(start 0.12065 -0.305054)
			(end 0.12065 -0.2794)
			(stroke
				(width 0.1)
				(type default)
			)
			(layer "B.Fab")
		)
		(fp_line
			(start -0.12065 -0.3048)
			(end -0.67945 -0.3048)
			(stroke
				(width 0.1)
				(type default)
			)
			(layer "B.Fab")
		)
		(fp_line
			(start -0.67945 -0.3048)
			(end -0.67945 0.3048)
			(stroke
				(width 0.1)
				(type default)
			)
			(layer "B.Fab")
		)
		(fp_line
			(start 0.12065 -0.2794)
			(end -0.12065 -0.2794)
			(stroke
				(width 0.1)
				(type default)
			)
			(layer "B.Fab")
		)
		(fp_line
			(start -0.12065 -0.2794)
			(end -0.12065 -0.3048)
			(stroke
				(width 0.1)
				(type default)
			)
			(layer "B.Fab")
		)
		(fp_line
			(start 0.12065 0.2794)
			(end 0.12065 0.3048)
			(stroke
				(width 0.1)
				(type default)
			)
			(layer "B.Fab")
		)
		(fp_line
			(start -0.120396 0.2794)
			(end 0.12065 0.2794)
			(stroke
				(width 0.1)
				(type default)
			)
			(layer "B.Fab")
		)
		(fp_line
			(start 0.67945 0.3048)
			(end 0.67945 -0.305054)
			(stroke
				(width 0.1)
				(type default)
			)
			(layer "B.Fab")
		)
		(fp_line
			(start 0.12065 0.3048)
			(end 0.67945 0.3048)
			(stroke
				(width 0.1)
				(type default)
			)
			(layer "B.Fab")
		)
		(fp_line
			(start -0.120396 0.3048)
			(end -0.120396 0.2794)
			(stroke
				(width 0.1)
				(type default)
			)
			(layer "B.Fab")
		)
		(fp_line
			(start -0.67945 0.3048)
			(end -0.120396 0.3048)
			(stroke
				(width 0.1)
				(type default)
			)
			(layer "B.Fab")
		)
		(pad "1" smd circle
			(at 0.40005 0 270)
			(size 0 0)
			(layers "B.Cu" "B.Mask" "B.Paste")
			(net "P3V3_AUX_USB_HUB_2")
		)
		(pad "2" smd circle
			(at -0.40005 0 270)
			(size 0 0)
			(layers "B.Cu" "B.Mask" "B.Paste")
			(net "GND")
		)
	)
	(footprint ""
		(layer "B.Cu")
		(at 375.578624 -190.703454 -90)
		(property "Reference" "R295"
			(at 0 0 90)
			(layer "B.SilkS")
			(hide yes)
			(effects
				(font
					(size 1.27 1.27)
				)
				(justify mirror)
			)
		)
		(property "Value" ""
			(at 0 0 90)
			(layer "B.Fab")
			(effects
				(font
					(size 1.27 1.27)
				)
				(justify mirror)
			)
		)
		(duplicate_pad_numbers_are_jumpers no)
		(fp_line
			(start -0.7874 0.4064)
			(end 0.7874 0.4064)
			(stroke
				(width 0.1524)
				(type default)
			)
			(layer "B.SilkS")
		)
		(fp_line
			(start 0.7874 0.4064)
			(end 0.7874 -0.4064)
			(stroke
				(width 0.1524)
				(type default)
			)
			(layer "B.SilkS")
		)
		(fp_line
			(start -0.7874 -0.4064)
			(end -0.7874 0.4064)
			(stroke
				(width 0.1524)
				(type default)
			)
			(layer "B.SilkS")
		)
		(fp_line
			(start 0.7874 -0.4064)
			(end -0.7874 -0.4064)
			(stroke
				(width 0.1524)
				(type default)
			)
			(layer "B.SilkS")
		)
		(fp_line
			(start -0.67945 0.3048)
			(end -0.120396 0.3048)
			(stroke
				(width 0.1)
				(type default)
			)
			(layer "B.Fab")
		)
		(fp_line
			(start -0.120396 0.3048)
			(end -0.120396 0.2794)
			(stroke
				(width 0.1)
				(type default)
			)
			(layer "B.Fab")
		)
		(fp_line
			(start 0.12065 0.3048)
			(end 0.67945 0.3048)
			(stroke
				(width 0.1)
				(type default)
			)
			(layer "B.Fab")
		)
		(fp_line
			(start 0.67945 0.3048)
			(end 0.67945 -0.305054)
			(stroke
				(width 0.1)
				(type default)
			)
			(layer "B.Fab")
		)
		(fp_line
			(start -0.120396 0.2794)
			(end 0.12065 0.2794)
			(stroke
				(width 0.1)
				(type default)
			)
			(layer "B.Fab")
		)
		(fp_line
			(start 0.12065 0.2794)
			(end 0.12065 0.3048)
			(stroke
				(width 0.1)
				(type default)
			)
			(layer "B.Fab")
		)
		(fp_line
			(start -0.12065 -0.2794)
			(end -0.12065 -0.3048)
			(stroke
				(width 0.1)
				(type default)
			)
			(layer "B.Fab")
		)
		(fp_line
			(start 0.12065 -0.2794)
			(end -0.12065 -0.2794)
			(stroke
				(width 0.1)
				(type default)
			)
			(layer "B.Fab")
		)
		(fp_line
			(start -0.67945 -0.3048)
			(end -0.67945 0.3048)
			(stroke
				(width 0.1)
				(type default)
			)
			(layer "B.Fab")
		)
		(fp_line
			(start -0.12065 -0.3048)
			(end -0.67945 -0.3048)
			(stroke
				(width 0.1)
				(type default)
			)
			(layer "B.Fab")
		)
		(fp_line
			(start 0.12065 -0.305054)
			(end 0.12065 -0.2794)
			(stroke
				(width 0.1)
				(type default)
			)
			(layer "B.Fab")
		)
		(fp_line
			(start 0.67945 -0.305054)
			(end 0.12065 -0.305054)
			(stroke
				(width 0.1)
				(type default)
			)
			(layer "B.Fab")
		)
		(pad "1" smd circle
			(at 0.40005 0 90)
			(size 0 0)
			(layers "B.Cu" "B.Mask" "B.Paste")
			(net "GND")
		)
		(pad "2" smd circle
			(at -0.40005 0 90)
			(size 0 0)
			(layers "B.Cu" "B.Mask" "B.Paste")
			(net "PD_CPU0_ENH_MCECC_DIS")
		)
	)
	(footprint ""
		(layer "B.Cu")
		(at 8.22198 -37.551868)
		(property "Reference" ""
			(at 0 0 0)
			(layer "B.SilkS")
			(hide yes)
			(effects
				(font
					(size 1.27 1.27)
				)
				(justify mirror)
			)
		)
		(property "Value" ""
			(at 0 0 0)
			(layer "B.Fab")
			(effects
				(font
					(size 1.27 1.27)
				)
				(justify mirror)
			)
		)
		(duplicate_pad_numbers_are_jumpers no)
		(pad "1" smd circle
			(at 0 0 180)
			(size 0.9906 0.9906)
			(layers "B.Cu" "B.Mask" "B.Paste")
			(net "Net_291")
		)
		(zone
			(layer "B.Cu")
			(hatch none 0.5)
			(connect_pads
				(clearance 0)
			)
			(min_thickness 0.25)
			(keepout
				(tracks not_allowed)
				(vias allowed)
				(pads allowed)
				(copperpour not_allowed)
				(footprints allowed)
			)
			(placement
				(enabled no)
				(sheetname "")
			)
			(fill
				(thermal_gap 0.5)
				(thermal_bridge_width 0.5)
				(island_removal_mode 0)
			)
			(polygon
				(pts
					(arc
						(start 9.84758 -37.551868)
						(mid 6.59638 -37.551868)
						(end 9.84758 -37.551868)
					)
				)
			)
		)
	)
	(footprint ""
		(layer "B.Cu")
		(at 311.84088 -54.320948)
		(property "Reference" "R4105"
			(at 0 0 0)
			(layer "B.SilkS")
			(hide yes)
			(effects
				(font
					(size 1.27 1.27)
				)
				(justify mirror)
			)
		)
		(property "Value" ""
			(at 0 0 0)
			(layer "B.Fab")
			(effects
				(font
					(size 1.27 1.27)
				)
				(justify mirror)
			)
		)
		(duplicate_pad_numbers_are_jumpers no)
		(fp_line
			(start -0.7874 -0.4064)
			(end -0.7874 0.4064)
			(stroke
				(width 0.1524)
				(type default)
			)
			(layer "B.SilkS")
		)
		(fp_line
			(start -0.7874 0.4064)
			(end 0.7874 0.4064)
			(stroke
				(width 0.1524)
				(type default)
			)
			(layer "B.SilkS")
		)
		(fp_line
			(start 0.7874 -0.4064)
			(end -0.7874 -0.4064)
			(stroke
				(width 0.1524)
				(type default)
			)
			(layer "B.SilkS")
		)
		(fp_line
			(start 0.7874 0.4064)
			(end 0.7874 -0.4064)
			(stroke
				(width 0.1524)
				(type default)
			)
			(layer "B.SilkS")
		)
		(fp_line
			(start -0.67945 -0.3048)
			(end -0.67945 0.3048)
			(stroke
				(width 0.1)
				(type default)
			)
			(layer "B.Fab")
		)
		(fp_line
			(start -0.67945 0.3048)
			(end -0.120396 0.3048)
			(stroke
				(width 0.1)
				(type default)
			)
			(layer "B.Fab")
		)
		(fp_line
			(start -0.12065 -0.3048)
			(end -0.67945 -0.3048)
			(stroke
				(width 0.1)
				(type default)
			)
			(layer "B.Fab")
		)
		(fp_line
			(start -0.12065 -0.2794)
			(end -0.12065 -0.3048)
			(stroke
				(width 0.1)
				(type default)
			)
			(layer "B.Fab")
		)
		(fp_line
			(start -0.120396 0.2794)
			(end 0.12065 0.2794)
			(stroke
				(width 0.1)
				(type default)
			)
			(layer "B.Fab")
		)
		(fp_line
			(start -0.120396 0.3048)
			(end -0.120396 0.2794)
			(stroke
				(width 0.1)
				(type default)
			)
			(layer "B.Fab")
		)
		(fp_line
			(start 0.12065 -0.305054)
			(end 0.12065 -0.2794)
			(stroke
				(width 0.1)
				(type default)
			)
			(layer "B.Fab")
		)
		(fp_line
			(start 0.12065 -0.2794)
			(end -0.12065 -0.2794)
			(stroke
				(width 0.1)
				(type default)
			)
			(layer "B.Fab")
		)
		(fp_line
			(start 0.12065 0.2794)
			(end 0.12065 0.3048)
			(stroke
				(width 0.1)
				(type default)
			)
			(layer "B.Fab")
		)
		(fp_line
			(start 0.12065 0.3048)
			(end 0.67945 0.3048)
			(stroke
				(width 0.1)
				(type default)
			)
			(layer "B.Fab")
		)
		(fp_line
			(start 0.67945 -0.305054)
			(end 0.12065 -0.305054)
			(stroke
				(width 0.1)
				(type default)
			)
			(layer "B.Fab")
		)
		(fp_line
			(start 0.67945 0.3048)
			(end 0.67945 -0.305054)
			(stroke
				(width 0.1)
				(type default)
			)
			(layer "B.Fab")
		)
		(pad "1" smd circle
			(at 0.40005 0 180)
			(size 0 0)
			(layers "B.Cu" "B.Mask" "B.Paste")
			(net "PD_GPP_M_15")
		)
		(pad "2" smd circle
			(at -0.40005 0 180)
			(size 0 0)
			(layers "B.Cu" "B.Mask" "B.Paste")
			(net "GND")
		)
	)
	(footprint ""
		(layer "B.Cu")
		(at 46.412658 -344.729054 -90)
		(property "Reference" "PC1203_P1_4"
			(at 0 0 90)
			(layer "B.SilkS")
			(hide yes)
			(effects
				(font
					(size 1.27 1.27)
				)
				(justify mirror)
			)
		)
		(property "Value" ""
			(at 0 0 90)
			(layer "B.Fab")
			(effects
				(font
					(size 1.27 1.27)
				)
				(justify mirror)
			)
		)
		(duplicate_pad_numbers_are_jumpers no)
		(fp_line
			(start -0.7874 0.4064)
			(end 0.7874 0.4064)
			(stroke
				(width 0.1524)
				(type default)
			)
			(layer "B.SilkS")
		)
		(fp_line
			(start 0.7874 0.4064)
			(end 0.7874 -0.4064)
			(stroke
				(width 0.1524)
				(type default)
			)
			(layer "B.SilkS")
		)
		(fp_line
			(start -0.7874 -0.4064)
			(end -0.7874 0.4064)
			(stroke
				(width 0.1524)
				(type default)
			)
			(layer "B.SilkS")
		)
		(fp_line
			(start 0.7874 -0.4064)
			(end -0.7874 -0.4064)
			(stroke
				(width 0.1524)
				(type default)
			)
			(layer "B.SilkS")
		)
		(fp_line
			(start -0.67945 0.3048)
			(end -0.120396 0.3048)
			(stroke
				(width 0.1)
				(type default)
			)
			(layer "B.Fab")
		)
		(fp_line
			(start -0.120396 0.3048)
			(end -0.120396 0.2794)
			(stroke
				(width 0.1)
				(type default)
			)
			(layer "B.Fab")
		)
		(fp_line
			(start 0.12065 0.3048)
			(end 0.67945 0.3048)
			(stroke
				(width 0.1)
				(type default)
			)
			(layer "B.Fab")
		)
		(fp_line
			(start 0.67945 0.3048)
			(end 0.67945 -0.305054)
			(stroke
				(width 0.1)
				(type default)
			)
			(layer "B.Fab")
		)
		(fp_line
			(start -0.120396 0.2794)
			(end 0.12065 0.2794)
			(stroke
				(width 0.1)
				(type default)
			)
			(layer "B.Fab")
		)
		(fp_line
			(start 0.12065 0.2794)
			(end 0.12065 0.3048)
			(stroke
				(width 0.1)
				(type default)
			)
			(layer "B.Fab")
		)
		(fp_line
			(start -0.12065 -0.2794)
			(end -0.12065 -0.3048)
			(stroke
				(width 0.1)
				(type default)
			)
			(layer "B.Fab")
		)
		(fp_line
			(start 0.12065 -0.2794)
			(end -0.12065 -0.2794)
			(stroke
				(width 0.1)
				(type default)
			)
			(layer "B.Fab")
		)
		(fp_line
			(start -0.67945 -0.3048)
			(end -0.67945 0.3048)
			(stroke
				(width 0.1)
				(type default)
			)
			(layer "B.Fab")
		)
		(fp_line
			(start -0.12065 -0.3048)
			(end -0.67945 -0.3048)
			(stroke
				(width 0.1)
				(type default)
			)
			(layer "B.Fab")
		)
		(fp_line
			(start 0.12065 -0.305054)
			(end 0.12065 -0.2794)
			(stroke
				(width 0.1)
				(type default)
			)
			(layer "B.Fab")
		)
		(fp_line
			(start 0.67945 -0.305054)
			(end 0.12065 -0.305054)
			(stroke
				(width 0.1)
				(type default)
			)
			(layer "B.Fab")
		)
		(pad "1" smd circle
			(at 0.40005 0 90)
			(size 0 0)
			(layers "B.Cu" "B.Mask" "B.Paste")
			(net "PVCCFA_EHV_FIVRA_CPU1")
		)
		(pad "2" smd circle
			(at -0.40005 0 90)
			(size 0 0)
			(layers "B.Cu" "B.Mask" "B.Paste")
			(net "GND")
		)
	)
)
